# Lightning_PEB_EQL.xlsx — USB2.0 (si-constraints)
|  |  | USB2.0 (diff pair 85±10% ohm ) |  | W/Sd=5.38/6.2 for outer layout and 5.25/7.5 for inner layer  W:trace width Sd:diff Pair space |  |  |  |  |  |  |  |  |  |  |  |  |  |  |  |  |  |  |  |  |  |
| Leopoard MB to HUB of Re-timer Card(by USB Cable) |  |  |  |  |  |  |  |  | SKT-USB13-119-GP(USB1~2) |  | SKT-USB7-18-GP(SKT1) |  |  |  |  |  |  |  |  |  |  |  |  |  |  |
| Leopard-BW |  |  |  |  |  |  |  |  | USB Connector | USB Cable | USB Connector | HUB of Re-timer Card(U14_USB2514B-AEZC-TR-GP-U) |  |  |  |  |  |  |  |  |  |  |  |  |  |
| Net Name | PKG Lengths | PCB Net Length | Differential Match | Net Name | PCB Net Length | Differential Match | MB Total Length | Differential Match | Pin of Connector | The Length of Cable | Pin of Connector | Net Name | PCB Net Length | Differential Match | Net Name | PCB Net Length | Differential Match | Net Name | PCB Net Length | Differential Match | Re-timer Card Total Length | Differential Match | Total Length | Differential Match |  |
| USB2_01_DP |  | 4369.49 |  | USB2_01_DP_FB | 485.03 |  | 4854.5199999999995 |  | USB1.3 |  | SKT1.3 | D85_USB_CON_DP | 619.95000000000005 |  | D85_RETIMER_USB_DP | 190.53 |  | D85_RETIMER_USB_R_DP | 297.45 |  | 1107.93 |  | 5962.45 |  |  |
| USB2_01_DN |  | 4369.22 | yes; within 10mil | USB2_01_DN_FB | 487.24 | yes; within 10mil | 4856.46 | yes; within 10mil | USB1.2 |  | SKT1.2 | D85_USB_CON_DN | 622.75 | yes; within 5mil | D85_RETIMER_USB_DN | 186.33 | yes; within 5mil | D85_RETIMER_USB_R_DN | 297.97000000000003 | yes; within 5mil | 1107.0500000000002 | yes; within 5mil | 5963.51 | yes; within 5 mils |  |
|  |  |  |  |  |  |  |  |  |  |  |  |  |  |  | D85_LEOPARD_USB_DP | 2597.9899999999998 |  | D85_RETIMER_USB_R_DP | 297.45 |  | 2895.4399999999996 |  |  |  |  |
|  |  |  |  |  |  |  |  |  |  |  |  |  |  |  | D85_LEOPARD_USB_DN | 2599.62 | yes; within 5mil | D85_RETIMER_USB_R_DN | 297.97000000000003 | yes; within 5mil | 2897.59 | yes; within 5mil |  |  |  |
| HUB of Re-timer Card to HUB of PEB(by MiniSAS HD Cable) |  |  |  |  |  |  |  |  | MLX-CONN144-12R-3-GP-U(CN3A~D) |  |  | MLX-CONN144-12R-3-GP-U(CN15A) |  |  |  |  |  |  |  |  |  |  |  |  |  |
| HUB of Re-timer Card(U14_USB2514B-AEZC-TR-GP-U) |  |  |  |  |  |  |  |  | MiniSAS HD Connector |  | MiniSAS HD Cable | MiniSAS HD Connector | BMC of PEB(U40C) |  |  |  |  |  |  |  |  |  |  |  |  |
| Net Name | PKG Lengths | PCB Net Length | Differential Match | Net Name | PCB Net Length | Differential Match | Re-timer Card Total Length | Differential Match | Pin of Connector |  | The Length of Cable | Pin of Connector | Net Name | PCB Net Length | Differential Match | Net Name | PCB Net Length | Differential Match | Net Name | PCB Net Length | Differential Match | PEB Total Length | Differential Match | Total Length | Differential Match |
| D85_USB_HUB_MINI_A_DP |  | 3092.92 |  | D85_USB_HUB_MINI_A_DP_R | 556.62 |  | 3649.54 |  | CN3A.AD2 |  |  | CN15A.AD2 | 8644_USB_DP1 | 503.64 |  | USB2_BMC_DP | 10275.43 |  | BMC_USB2_HDP | 245.4 |  | 11024.47 |  | 14674.009999999998 |  |
| D85_USB_HUB_MINI_A_DN |  | 3090.3 | yes; within 10mil | D85_USB_HUB_MINI_A_DN_R | 555.03 | yes; within 10mil | 3645.33 | yes; within 10mil | CN3A.AD1 |  |  | CN15A.AD1 | 8644_USB_DN1 | 502.76 | yes; within 1mil | USB2_BMC_DN | 10276 | yes; within 1mil | BMC_USB2_HDN | 246.33 | yes; within 1mil | 11025.09 | yes; within 1mil | 14670.42 | yes; within 5 mils |
| D85_USB_HUB_MINI_B_DP |  | 3072.53 |  | D85_USB_HUB_MINI_B_DP_R | 1113.3 |  | 4185.83 |  | CN3B.BD2 |  |  | MLX-CONN144-12R-3-GP-U(CN16A) |  |  |  |  |  |  |  |  |  |  |  |  |  |
| D85_USB_HUB_MINI_B_DN |  | 3072.58 | yes; within 10mil | D85_USB_HUB_MINI_B_DN_R | 1114.1199999999999 | yes; within 10mil | 4186.7 | yes; within 10mil | CN3B.BD1 |  | MiniSAS HD Cable | MiniSAS HD Connector | BMC of PEB(U40C) |  |  |  |  |  |  |  |  |  |  |  |  |
|  |  |  |  |  |  |  |  |  |  |  | The Length of Cable | Pin of Connector | Net Name | PCB Net Length | Differential Match | Net Name | PCB Net Length | Differential Match | Net Name | PCB Net Length | Differential Match | PEB Total Length | Differential Match | Total Length | Differential Match |
| D85_USB_HUB_MINI_C_DP |  | 3242.12 |  | D85_USB_HUB_MINI_C_DP_R | 1532.01 |  | 4774.13 |  | CN3C.CD2 |  |  | CN16A.AD2 | 8644_USB_DP5 | 799.51 |  | USB_P4_DP_BMC | 14325.37 |  | BMC_USB1_HDP2 | 307.83999999999997 |  | 15432.720000000001 |  | 19082.260000000002 |  |
| D85_USB_HUB_MINI_C_DN |  | 3242.65 | yes; within 10mil | D85_USB_HUB_MINI_C_DN_R | 1529.14 | yes; within 10mil | 4771.79 | yes; within 10mil | CN3C.CD1 |  |  | CN16A.AD1 | 8644_USB_DN5 | 800.08 | yes; within 1mil | USB_P4_DN_BMC | 14325.45 | yes; within 1mil | BMC_USB1_HDN2 | 307.14999999999998 | yes; within 1mil | 15432.68 | yes; within 1mil | 19078.010000000002 | yes; within 5 mils |
| D85_USB_HUB_MINI_D_DP |  | 3464.11 |  | D85_USB_HUB_MINI_D_DP_R | 2143.75 |  | 5607.8600000000006 |  | CN3D.DD2 |  |  |  |  |  |  |  |  |  |  |  |  |  |  |  |  |
| D85_USB_HUB_MINI_D_DN |  | 3462.46 | yes; within 10mil | D85_USB_HUB_MINI_D_DN_R | 2142.94 | yes; within 10mil | 5605.4 | yes; within 10mil | CN3D.DD1 |  |  |  |  |  |  |  |  |  |  |  |  |  |  |  |  |
| USB Connector(T-USB-250-GP_SKT1) | BMC of PEB(U40C) |  |  |  |  |  |  |  |  |  |  |  |  |  |  |  |  |  |  |  |  |  |  |  |  |
| Pin of Connector | Net Name | PCB Net Length | Differential Match | Net Name | PCB Net Length | Differential Match | Net Name | PCB Net Length | Differential Match | Net Name | PCB Net Length | Differential Match | Total Length | Differential Match |  |  |  |  |  |  |  |  |  |  |  |
| SKT1.3 | USB_P1_F_DP1 | 580.58000000000004 |  | USB_DP_R | 559.30999999999995 |  | USB_P2_DP | 4309.0200000000004 |  | BMC_USB1_HDP | 309.77 |  | 5758.68 |  |  |  |  |  |  |  |  |  |  |  |  |
| SKT1.2 | USB_P1_F_DN1 | 580.76 | yes; within 1mil | USB_DN_R | 559.01 | yes; within 1mil | USB_P2_DN | 4309.84 | yes; within 1mil | BMC_USB1_HDN | 309.63 | yes; within 1mil | 5759.2400000000007 | yes; within 1mil |  |  |  |  |  |  |  |  |  |  |  |
